# S9S_MB_2U (Grand Teton) — schematic netlist excerpt (pin names and nets, part order shuffled) for the footprints in the layout excerpt that follows; sources: Cadence DE-HDL packaged netlist, KiCad conversion of 03242023_DA0F0TMBIJ0_F0T_Motherboard_J_brd_V01_OCP.brd

C1810  Q_CAP  0.1UF 25V 10% X7R  pkg 0402  page 162 : A = P3V3_AUX ; B = GND
R4893  Q_RES  49.9 1% EMPTY  pkg 0402LF  page 305 : A = P12V_HSC_TEMP_E ; B = P12V_HSC_TEMP_D-

(kicad_pcb
	(version 20260206)
	(generator "pcbnew")
	(generator_version "10.0")
	(general
		(thickness 1.6)
		(legacy_teardrops no)
	)
	(paper "A4")
	(title_block
		(title "03242023_DA0F0TMBIJ0_F0T_Motherboard_J_brd_V01_OCP.brd")
		(comment 1 "Grand Teton / footprints 4108-4109 of 6105")
	)
	(layers
		(0 "F.Cu" signal "TOP")
		(4 "In1.Cu" signal "GND")
		(6 "In2.Cu" signal "IN1")
		(8 "In3.Cu" signal "GND1")
		(10 "In4.Cu" signal "IN2")
		(12 "In5.Cu" signal "GND2")
		(14 "In6.Cu" signal "IN3")
		(16 "In7.Cu" signal "GND3")
		(18 "In8.Cu" signal "VCC")
		(20 "In9.Cu" signal "VCC1")
		(22 "In10.Cu" signal "GND4")
		(24 "In11.Cu" signal "IN4")
		(26 "In12.Cu" signal "GND5")
		(28 "In13.Cu" signal "IN5")
		(30 "In14.Cu" signal "GND6")
		(32 "In15.Cu" signal "IN6")
		(34 "In16.Cu" signal "GND7")
		(2 "B.Cu" signal "BOTTOM")
		(9 "F.Adhes" user "F.Adhesive")
		(11 "B.Adhes" user "B.Adhesive")
		(13 "F.Paste" user "Package Geometry/Pastemask Top")
		(15 "B.Paste" user "Package Geometry/Pastemask Bottom")
		(5 "F.SilkS" user "Ref Des/Silkscreen Top")
		(7 "B.SilkS" user "Ref Des/Silkscreen Bottom")
		(1 "F.Mask" user "Board Geometry/Soldermask Top")
		(3 "B.Mask" user "Board Geometry/Soldermask Bottom")
		(17 "Dwgs.User" user "User.Drawings")
		(19 "Cmts.User" user "User.Comments")
		(21 "Eco1.User" user "User.Eco1")
		(23 "Eco2.User" user "User.Eco2")
		(25 "Edge.Cuts" user "Board Geometry/Outline")
		(27 "Margin" user)
		(31 "F.CrtYd" user "Package Geometry/Place Bound Top")
		(29 "B.CrtYd" user "Package Geometry/Place Bound Bottom")
		(35 "F.Fab" user "Ref Des/Assembly Top")
		(33 "B.Fab" user "Ref Des/Assembly Bottom")
	)
	(footprint ""
		(layer "F.Cu")
		(at 28.578048 -71.88073)
		(property "Reference" "C1810"
			(at 0 0 0)
			(layer "F.SilkS")
			(hide yes)
			(effects
				(font
					(size 1.27 1.27)
				)
			)
		)
		(property "Value" ""
			(at 0 0 0)
			(layer "F.Fab")
			(effects
				(font
					(size 1.27 1.27)
				)
			)
		)
		(duplicate_pad_numbers_are_jumpers no)
		(fp_line
			(start -0.7874 -0.4064)
			(end 0.7874 -0.4064)
			(stroke
				(width 0.1524)
				(type default)
			)
			(layer "F.SilkS")
		)
		(fp_line
			(start -0.7874 0.4064)
			(end -0.7874 -0.4064)
			(stroke
				(width 0.1524)
				(type default)
			)
			(layer "F.SilkS")
		)
		(fp_line
			(start 0.7874 -0.4064)
			(end 0.7874 0.4064)
			(stroke
				(width 0.1524)
				(type default)
			)
			(layer "F.SilkS")
		)
		(fp_line
			(start 0.7874 0.4064)
			(end -0.7874 0.4064)
			(stroke
				(width 0.1524)
				(type default)
			)
			(layer "F.SilkS")
		)
		(fp_line
			(start -0.67945 -0.305054)
			(end -0.12065 -0.305054)
			(stroke
				(width 0.1)
				(type default)
			)
			(layer "F.Fab")
		)
		(fp_line
			(start -0.67945 0.3048)
			(end -0.67945 -0.305054)
			(stroke
				(width 0.1)
				(type default)
			)
			(layer "F.Fab")
		)
		(fp_line
			(start -0.12065 -0.305054)
			(end -0.12065 -0.2794)
			(stroke
				(width 0.1)
				(type default)
			)
			(layer "F.Fab")
		)
		(fp_line
			(start -0.12065 -0.2794)
			(end 0.12065 -0.2794)
			(stroke
				(width 0.1)
				(type default)
			)
			(layer "F.Fab")
		)
		(fp_line
			(start -0.12065 0.2794)
			(end -0.12065 0.3048)
			(stroke
				(width 0.1)
				(type default)
			)
			(layer "F.Fab")
		)
		(fp_line
			(start -0.12065 0.3048)
			(end -0.67945 0.3048)
			(stroke
				(width 0.1)
				(type default)
			)
			(layer "F.Fab")
		)
		(fp_line
			(start 0.120396 0.2794)
			(end -0.12065 0.2794)
			(stroke
				(width 0.1)
				(type default)
			)
			(layer "F.Fab")
		)
		(fp_line
			(start 0.120396 0.3048)
			(end 0.120396 0.2794)
			(stroke
				(width 0.1)
				(type default)
			)
			(layer "F.Fab")
		)
		(fp_line
			(start 0.12065 -0.3048)
			(end 0.67945 -0.3048)
			(stroke
				(width 0.1)
				(type default)
			)
			(layer "F.Fab")
		)
		(fp_line
			(start 0.12065 -0.2794)
			(end 0.12065 -0.3048)
			(stroke
				(width 0.1)
				(type default)
			)
			(layer "F.Fab")
		)
		(fp_line
			(start 0.67945 -0.3048)
			(end 0.67945 0.3048)
			(stroke
				(width 0.1)
				(type default)
			)
			(layer "F.Fab")
		)
		(fp_line
			(start 0.67945 0.3048)
			(end 0.120396 0.3048)
			(stroke
				(width 0.1)
				(type default)
			)
			(layer "F.Fab")
		)
		(pad "1" smd circle
			(at -0.40005 0)
			(size 0 0)
			(layers "F.Cu" "F.Mask" "F.Paste")
			(net "P3V3_AUX")
		)
		(pad "2" smd circle
			(at 0.40005 0)
			(size 0 0)
			(layers "F.Cu" "F.Mask" "F.Paste")
			(net "GND")
		)
	)
	(footprint ""
		(layer "F.Cu")
		(at 284.62732 -408.53868)
		(property "Reference" "R4893"
			(at 0 0 0)
			(layer "F.SilkS")
			(hide yes)
			(effects
				(font
					(size 1.27 1.27)
				)
			)
		)
		(property "Value" ""
			(at 0 0 0)
			(layer "F.Fab")
			(effects
				(font
					(size 1.27 1.27)
				)
			)
		)
		(duplicate_pad_numbers_are_jumpers no)
		(fp_line
			(start -0.7874 -0.4064)
			(end 0.7874 -0.4064)
			(stroke
				(width 0.1524)
				(type default)
			)
			(layer "F.SilkS")
		)
		(fp_line
			(start -0.7874 0.4064)
			(end -0.7874 -0.4064)
			(stroke
				(width 0.1524)
				(type default)
			)
			(layer "F.SilkS")
		)
		(fp_line
			(start 0.7874 -0.4064)
			(end 0.7874 0.4064)
			(stroke
				(width 0.1524)
				(type default)
			)
			(layer "F.SilkS")
		)
		(fp_line
			(start 0.7874 0.4064)
			(end -0.7874 0.4064)
			(stroke
				(width 0.1524)
				(type default)
			)
			(layer "F.SilkS")
		)
		(fp_line
			(start -0.67945 -0.305054)
			(end -0.12065 -0.305054)
			(stroke
				(width 0.1)
				(type default)
			)
			(layer "F.Fab")
		)
		(fp_line
			(start -0.67945 0.3048)
			(end -0.67945 -0.305054)
			(stroke
				(width 0.1)
				(type default)
			)
			(layer "F.Fab")
		)
		(fp_line
			(start -0.12065 -0.305054)
			(end -0.12065 -0.2794)
			(stroke
				(width 0.1)
				(type default)
			)
			(layer "F.Fab")
		)
		(fp_line
			(start -0.12065 -0.2794)
			(end 0.12065 -0.2794)
			(stroke
				(width 0.1)
				(type default)
			)
			(layer "F.Fab")
		)
		(fp_line
			(start -0.12065 0.2794)
			(end -0.12065 0.3048)
			(stroke
				(width 0.1)
				(type default)
			)
			(layer "F.Fab")
		)
		(fp_line
			(start -0.12065 0.3048)
			(end -0.67945 0.3048)
			(stroke
				(width 0.1)
				(type default)
			)
			(layer "F.Fab")
		)
		(fp_line
			(start 0.120396 0.2794)
			(end -0.12065 0.2794)
			(stroke
				(width 0.1)
				(type default)
			)
			(layer "F.Fab")
		)
		(fp_line
			(start 0.120396 0.3048)
			(end 0.120396 0.2794)
			(stroke
				(width 0.1)
				(type default)
			)
			(layer "F.Fab")
		)
		(fp_line
			(start 0.12065 -0.3048)
			(end 0.67945 -0.3048)
			(stroke
				(width 0.1)
				(type default)
			)
			(layer "F.Fab")
		)
		(fp_line
			(start 0.12065 -0.2794)
			(end 0.12065 -0.3048)
			(stroke
				(width 0.1)
				(type default)
			)
			(layer "F.Fab")
		)
		(fp_line
			(start 0.67945 -0.3048)
			(end 0.67945 0.3048)
			(stroke
				(width 0.1)
				(type default)
			)
			(layer "F.Fab")
		)
		(fp_line
			(start 0.67945 0.3048)
			(end 0.120396 0.3048)
			(stroke
				(width 0.1)
				(type default)
			)
			(layer "F.Fab")
		)
		(pad "1" smd circle
			(at -0.40005 0)
			(size 0 0)
			(layers "F.Cu" "F.Mask" "F.Paste")
			(net "P12V_HSC_TEMP_E")
		)
		(pad "2" smd circle
			(at 0.40005 0)
			(size 0 0)
			(layers "F.Cu" "F.Mask" "F.Paste")
			(net "P12V_HSC_TEMP_D-")
		)
	)
)
